# BASEBOARD_FAB2 (Tioga Pass) — schematic netlist excerpt (pin names and nets, part order shuffled) for the footprints in the layout excerpt that follows; sources: Cadence DE-HDL packaged netlist, KiCad conversion of Wiwynn_Tioga_Pass_MB.brd

C25W16  CAP  100.0PF 50V 5% COG  pkg 0402LF  page 151 : A = P1V2_AUX_BMC ; B = GND
R4P5  RES  10.0K 1% CHIP  pkg 0402  page 97 : A = GND ; B = PD_CPU0_MCP01_DMON
C7P12  CAP_A  22.0UF 4V 20% X6S  pkg 0603V  page 76 : A = PVCCIO_CPU1 ; B = GND

(kicad_pcb
	(version 20260206)
	(generator "pcbnew")
	(generator_version "10.0")
	(general
		(thickness 1.6)
		(legacy_teardrops no)
	)
	(paper "A4")
	(title_block
		(title "Wiwynn_Tioga_Pass_MB.brd")
		(comment 1 "Tioga Pass / footprints 3183-3185 of 4770")
	)
	(layers
		(0 "F.Cu" signal "TOP")
		(4 "In1.Cu" signal "L2GND")
		(6 "In2.Cu" signal "L3")
		(8 "In3.Cu" signal "L4GND")
		(10 "In4.Cu" signal "L5")
		(12 "In5.Cu" signal "L6GND")
		(14 "In6.Cu" signal "L7VCC")
		(16 "In7.Cu" signal "L8VCC")
		(18 "In8.Cu" signal "L9GND")
		(20 "In9.Cu" signal "L10")
		(22 "In10.Cu" signal "L11GND")
		(24 "In11.Cu" signal "L12")
		(26 "In12.Cu" signal "L13GND")
		(2 "B.Cu" signal "BOTTOM")
		(9 "F.Adhes" user "F.Adhesive")
		(11 "B.Adhes" user "B.Adhesive")
		(13 "F.Paste" user "Package Geometry/Pastemask Top")
		(15 "B.Paste" user "Package Geometry/Pastemask Bottom")
		(5 "F.SilkS" user "Ref Des/Silkscreen Top")
		(7 "B.SilkS" user "Ref Des/Silkscreen Bottom")
		(1 "F.Mask" user "Board Geometry/Soldermask Top")
		(3 "B.Mask" user "Board Geometry/Soldermask Bottom")
		(17 "Dwgs.User" user "User.Drawings")
		(19 "Cmts.User" user "User.Comments")
		(21 "Eco1.User" user "User.Eco1")
		(23 "Eco2.User" user "User.Eco2")
		(25 "Edge.Cuts" user "Board Geometry/Outline")
		(27 "Margin" user)
		(31 "F.CrtYd" user "Package Geometry/Place Bound Top")
		(29 "B.CrtYd" user "Package Geometry/Place Bound Bottom")
		(35 "F.Fab" user "Ref Des/Assembly Top")
		(33 "B.Fab" user "Ref Des/Assembly Bottom")
	)
	(footprint ""
		(layer "B.Cu")
		(at 281.3812 -76.4794 90)
		(property "Reference" "R4P5"
			(at 0 0 90)
			(layer "B.SilkS")
			(hide yes)
			(effects
				(font
					(size 1.27 1.27)
				)
				(justify mirror)
			)
		)
		(property "Value" ""
			(at 0 0 90)
			(layer "B.Fab")
			(effects
				(font
					(size 1.27 1.27)
				)
				(justify mirror)
			)
		)
		(duplicate_pad_numbers_are_jumpers no)
		(fp_rect
			(start -0.2794 -0.1016)
			(end 0.2794 0.9906)
			(stroke
				(width 0)
				(type default)
			)
			(fill no)
			(layer "B.CrtYd")
		)
		(fp_line
			(start 0.2794 -0.1016)
			(end 0.2794 0.9906)
			(stroke
				(width 0.1)
				(type default)
			)
			(layer "B.Fab")
		)
		(fp_line
			(start -0.2794 -0.1016)
			(end 0.2794 -0.1016)
			(stroke
				(width 0.1)
				(type default)
			)
			(layer "B.Fab")
		)
		(fp_line
			(start 0.2794 0.9906)
			(end -0.2794 0.9906)
			(stroke
				(width 0.1)
				(type default)
			)
			(layer "B.Fab")
		)
		(fp_line
			(start -0.2794 0.9906)
			(end -0.2794 -0.1016)
			(stroke
				(width 0.1)
				(type default)
			)
			(layer "B.Fab")
		)
		(pad "1" smd rect
			(at 0 0 270)
			(size 0.508 0.508)
			(layers "B.Cu" "B.Mask" "B.Paste")
			(net "GND")
		)
		(pad "2" smd rect
			(at 0 0.889 270)
			(size 0.508 0.508)
			(layers "B.Cu" "B.Mask" "B.Paste")
			(net "PD_CPU0_MCP01_DMON")
		)
		(zone
			(layer "B.Cu")
			(hatch none 0.5)
			(connect_pads
				(clearance 0)
			)
			(min_thickness 0.25)
			(keepout
				(tracks allowed)
				(vias not_allowed)
				(pads allowed)
				(copperpour not_allowed)
				(footprints allowed)
			)
			(placement
				(enabled no)
				(sheetname "")
			)
			(fill
				(thermal_gap 0.5)
				(thermal_bridge_width 0.5)
				(island_removal_mode 0)
			)
			(polygon
				(pts
					(xy 281.6352 -76.2254) (xy 282.0162 -76.2254) (xy 282.0162 -76.7334) (xy 281.6352 -76.7334)
				)
			)
		)
		(zone
			(layer "B.Cu")
			(hatch none 0.5)
			(connect_pads
				(clearance 0)
			)
			(min_thickness 0.25)
			(keepout
				(tracks not_allowed)
				(vias allowed)
				(pads allowed)
				(copperpour not_allowed)
				(footprints allowed)
			)
			(placement
				(enabled no)
				(sheetname "")
			)
			(fill
				(thermal_gap 0.5)
				(thermal_bridge_width 0.5)
				(island_removal_mode 0)
			)
			(polygon
				(pts
					(xy 281.6352 -76.2254) (xy 282.0162 -76.2254) (xy 282.0162 -76.7334) (xy 281.6352 -76.7334)
				)
			)
		)
	)
	(footprint ""
		(layer "B.Cu")
		(at 115.353592 -77.366114)
		(property "Reference" "C7P12"
			(at 0 0 0)
			(layer "B.SilkS")
			(hide yes)
			(effects
				(font
					(size 1.27 1.27)
				)
				(justify mirror)
			)
		)
		(property "Value" ""
			(at 0 0 0)
			(layer "B.Fab")
			(effects
				(font
					(size 1.27 1.27)
				)
				(justify mirror)
			)
		)
		(duplicate_pad_numbers_are_jumpers no)
		(fp_poly
			(pts
				(xy 0.4953 -0.2032) (xy -0.4953 -0.2032) (xy -0.4953 1.6002) (xy 0.4953 1.6002)
			)
			(stroke
				(width 0)
				(type default)
			)
			(fill no)
			(layer "B.CrtYd")
		)
		(fp_line
			(start -0.4953 -0.2032)
			(end -0.4953 1.6002)
			(stroke
				(width 0.1)
				(type default)
			)
			(layer "B.Fab")
		)
		(fp_line
			(start -0.4953 1.6002)
			(end 0.4953 1.6002)
			(stroke
				(width 0.1)
				(type default)
			)
			(layer "B.Fab")
		)
		(fp_line
			(start 0.4953 -0.2032)
			(end -0.4953 -0.2032)
			(stroke
				(width 0.1)
				(type default)
			)
			(layer "B.Fab")
		)
		(fp_line
			(start 0.4953 1.6002)
			(end 0.4953 -0.2032)
			(stroke
				(width 0.1)
				(type default)
			)
			(layer "B.Fab")
		)
		(pad "1" smd rect
			(at 0 0 180)
			(size 0.762 0.889)
			(layers "B.Cu" "B.Mask" "B.Paste")
			(net "PVCCIO_CPU1")
		)
		(pad "2" smd rect
			(at 0 1.397 180)
			(size 0.762 0.889)
			(layers "B.Cu" "B.Mask" "B.Paste")
			(net "GND")
		)
		(zone
			(layer "B.Cu")
			(hatch none 0.5)
			(connect_pads
				(clearance 0)
			)
			(min_thickness 0.25)
			(keepout
				(tracks not_allowed)
				(vias allowed)
				(pads allowed)
				(copperpour not_allowed)
				(footprints allowed)
			)
			(placement
				(enabled no)
				(sheetname "")
			)
			(fill
				(thermal_gap 0.5)
				(thermal_bridge_width 0.5)
				(island_removal_mode 0)
			)
			(polygon
				(pts
					(xy 115.734592 -76.921614) (xy 114.972592 -76.921614) (xy 114.972592 -76.413614) (xy 115.734592 -76.413614)
				)
			)
		)
	)
	(footprint ""
		(layer "B.Cu")
		(at 442.0362 -24.2824)
		(property "Reference" "C25W16"
			(at 0.8382 -0.67818 0)
			(unlocked yes)
			(layer "B.SilkS")
			(effects
				(font
					(size 0.4064 0.254)
					(thickness 0.1524)
				)
				(justify left mirror)
			)
		)
		(property "Value" ""
			(at 0 0 0)
			(layer "B.Fab")
			(effects
				(font
					(size 1.27 1.27)
				)
				(justify mirror)
			)
		)
		(duplicate_pad_numbers_are_jumpers no)
		(fp_poly
			(pts
				(xy -0.3048 -0.1016) (xy -0.3048 0.9906) (xy 0.3048 0.9906) (xy 0.3048 -0.1016)
			)
			(stroke
				(width 0)
				(type default)
			)
			(fill no)
			(layer "B.CrtYd")
		)
		(fp_line
			(start -0.3048 -0.1016)
			(end 0.3048 -0.1016)
			(stroke
				(width 0.1)
				(type default)
			)
			(layer "B.Fab")
		)
		(fp_line
			(start -0.3048 0.9906)
			(end -0.3048 -0.1016)
			(stroke
				(width 0.1)
				(type default)
			)
			(layer "B.Fab")
		)
		(fp_line
			(start 0.3048 -0.1016)
			(end 0.3048 0.9906)
			(stroke
				(width 0.1)
				(type default)
			)
			(layer "B.Fab")
		)
		(fp_line
			(start 0.3048 0.9906)
			(end -0.3048 0.9906)
			(stroke
				(width 0.1)
				(type default)
			)
			(layer "B.Fab")
		)
		(pad "1" smd rect
			(at 0 0 180)
			(size 0.508 0.508)
			(layers "B.Cu" "B.Mask" "B.Paste")
			(net "P1V2_AUX_BMC")
		)
		(pad "2" smd rect
			(at 0 0.889 180)
			(size 0.508 0.508)
			(layers "B.Cu" "B.Mask" "B.Paste")
			(net "GND")
		)
		(zone
			(layer "B.Cu")
			(hatch none 0.5)
			(connect_pads
				(clearance 0)
			)
			(min_thickness 0.25)
			(keepout
				(tracks allowed)
				(vias not_allowed)
				(pads allowed)
				(copperpour not_allowed)
				(footprints allowed)
			)
			(placement
				(enabled no)
				(sheetname "")
			)
			(fill
				(thermal_gap 0.5)
				(thermal_bridge_width 0.5)
				(island_removal_mode 0)
			)
			(polygon
				(pts
					(xy 442.2902 -24.0284) (xy 441.7822 -24.0284) (xy 441.7822 -23.6474) (xy 442.2902 -23.6474)
				)
			)
		)
		(zone
			(layer "B.Cu")
			(hatch none 0.5)
			(connect_pads
				(clearance 0)
			)
			(min_thickness 0.25)
			(keepout
				(tracks not_allowed)
				(vias allowed)
				(pads allowed)
				(copperpour not_allowed)
				(footprints allowed)
			)
			(placement
				(enabled no)
				(sheetname "")
			)
			(fill
				(thermal_gap 0.5)
				(thermal_bridge_width 0.5)
				(island_removal_mode 0)
			)
			(polygon
				(pts
					(xy 442.2902 -23.6474) (xy 441.7822 -23.6474) (xy 441.7822 -24.0284) (xy 442.2902 -24.0284)
				)
			)
		)
	)
)
